(kicad_pcb
	(version 20260206)
	(generator "pcbnew")
	(generator_version "10.0")
	(general
		(thickness 1.6)
		(legacy_teardrops no)
	)
	(paper "A4")
	(title_block
		(title "03242023_DA0F0TMBIJ0_F0T_Motherboard_J_brd_V01_OCP.brd")
		(comment 1 "Grand Teton / footprints 5477-5484 of 6105")
	)
	(layers
		(0 "F.Cu" signal "TOP")
		(4 "In1.Cu" signal "GND")
		(6 "In2.Cu" signal "IN1")
		(8 "In3.Cu" signal "GND1")
		(10 "In4.Cu" signal "IN2")
		(12 "In5.Cu" signal "GND2")
		(14 "In6.Cu" signal "IN3")
		(16 "In7.Cu" signal "GND3")
		(18 "In8.Cu" signal "VCC")
		(20 "In9.Cu" signal "VCC1")
		(22 "In10.Cu" signal "GND4")
		(24 "In11.Cu" signal "IN4")
		(26 "In12.Cu" signal "GND5")
		(28 "In13.Cu" signal "IN5")
		(30 "In14.Cu" signal "GND6")
		(32 "In15.Cu" signal "IN6")
		(34 "In16.Cu" signal "GND7")
		(2 "B.Cu" signal "BOTTOM")
		(9 "F.Adhes" user "F.Adhesive")
		(11 "B.Adhes" user "B.Adhesive")
		(13 "F.Paste" user "Package Geometry/Pastemask Top")
		(15 "B.Paste" user "Package Geometry/Pastemask Bottom")
		(5 "F.SilkS" user "Ref Des/Silkscreen Top")
		(7 "B.SilkS" user "Ref Des/Silkscreen Bottom")
		(1 "F.Mask" user "Board Geometry/Soldermask Top")
		(3 "B.Mask" user "Board Geometry/Soldermask Bottom")
		(17 "Dwgs.User" user "User.Drawings")
		(19 "Cmts.User" user "User.Comments")
		(21 "Eco1.User" user "User.Eco1")
		(23 "Eco2.User" user "User.Eco2")
		(25 "Edge.Cuts" user "Board Geometry/Outline")
		(27 "Margin" user)
		(31 "F.CrtYd" user "Package Geometry/Place Bound Top")
		(29 "B.CrtYd" user "Package Geometry/Place Bound Bottom")
		(35 "F.Fab" user "Ref Des/Assembly Top")
		(33 "B.Fab" user "Ref Des/Assembly Bottom")
	)
	(footprint ""
		(layer "B.Cu")
		(at 9.99363 -318.6176)
		(property "Reference" "R48"
			(at 0 0 0)
			(layer "B.SilkS")
			(hide yes)
			(effects
				(font
					(size 1.27 1.27)
				)
				(justify mirror)
			)
		)
		(property "Value" ""
			(at 0 0 0)
			(layer "B.Fab")
			(effects
				(font
					(size 1.27 1.27)
				)
				(justify mirror)
			)
		)
		(duplicate_pad_numbers_are_jumpers no)
		(fp_line
			(start -0.7874 -0.4064)
			(end -0.7874 0.4064)
			(stroke
				(width 0.1524)
				(type default)
			)
			(layer "B.SilkS")
		)
		(fp_line
			(start -0.7874 0.4064)
			(end 0.7874 0.4064)
			(stroke
				(width 0.1524)
				(type default)
			)
			(layer "B.SilkS")
		)
		(fp_line
			(start 0.7874 -0.4064)
			(end -0.7874 -0.4064)
			(stroke
				(width 0.1524)
				(type default)
			)
			(layer "B.SilkS")
		)
		(fp_line
			(start 0.7874 0.4064)
			(end 0.7874 -0.4064)
			(stroke
				(width 0.1524)
				(type default)
			)
			(layer "B.SilkS")
		)
		(fp_line
			(start -0.67945 -0.3048)
			(end -0.67945 0.3048)
			(stroke
				(width 0.1)
				(type default)
			)
			(layer "B.Fab")
		)
		(fp_line
			(start -0.67945 0.3048)
			(end -0.120396 0.3048)
			(stroke
				(width 0.1)
				(type default)
			)
			(layer "B.Fab")
		)
		(fp_line
			(start -0.12065 -0.3048)
			(end -0.67945 -0.3048)
			(stroke
				(width 0.1)
				(type default)
			)
			(layer "B.Fab")
		)
		(fp_line
			(start -0.12065 -0.2794)
			(end -0.12065 -0.3048)
			(stroke
				(width 0.1)
				(type default)
			)
			(layer "B.Fab")
		)
		(fp_line
			(start -0.120396 0.2794)
			(end 0.12065 0.2794)
			(stroke
				(width 0.1)
				(type default)
			)
			(layer "B.Fab")
		)
		(fp_line
			(start -0.120396 0.3048)
			(end -0.120396 0.2794)
			(stroke
				(width 0.1)
				(type default)
			)
			(layer "B.Fab")
		)
		(fp_line
			(start 0.12065 -0.305054)
			(end 0.12065 -0.2794)
			(stroke
				(width 0.1)
				(type default)
			)
			(layer "B.Fab")
		)
		(fp_line
			(start 0.12065 -0.2794)
			(end -0.12065 -0.2794)
			(stroke
				(width 0.1)
				(type default)
			)
			(layer "B.Fab")
		)
		(fp_line
			(start 0.12065 0.2794)
			(end 0.12065 0.3048)
			(stroke
				(width 0.1)
				(type default)
			)
			(layer "B.Fab")
		)
		(fp_line
			(start 0.12065 0.3048)
			(end 0.67945 0.3048)
			(stroke
				(width 0.1)
				(type default)
			)
			(layer "B.Fab")
		)
		(fp_line
			(start 0.67945 -0.305054)
			(end 0.12065 -0.305054)
			(stroke
				(width 0.1)
				(type default)
			)
			(layer "B.Fab")
		)
		(fp_line
			(start 0.67945 0.3048)
			(end 0.67945 -0.305054)
			(stroke
				(width 0.1)
				(type default)
			)
			(layer "B.Fab")
		)
		(pad "1" smd circle
			(at 0.40005 0 180)
			(size 0 0)
			(layers "B.Cu" "B.Mask" "B.Paste")
			(net "PD_CHD_CPU1_DIMM1_SAA")
		)
		(pad "2" smd circle
			(at -0.40005 0 180)
			(size 0 0)
			(layers "B.Cu" "B.Mask" "B.Paste")
			(net "GND")
		)
	)
	(footprint ""
		(layer "B.Cu")
		(at 278.724614 -321.549776 -90)
		(property "Reference" "C19"
			(at 0 0 90)
			(layer "B.SilkS")
			(hide yes)
			(effects
				(font
					(size 1.27 1.27)
				)
				(justify mirror)
			)
		)
		(property "Value" ""
			(at 0 0 90)
			(layer "B.Fab")
			(effects
				(font
					(size 1.27 1.27)
				)
				(justify mirror)
			)
		)
		(duplicate_pad_numbers_are_jumpers no)
		(fp_line
			(start -1.524 0.762)
			(end 1.524 0.762)
			(stroke
				(width 0.1524)
				(type default)
			)
			(layer "B.SilkS")
		)
		(fp_line
			(start 1.524 0.762)
			(end 1.524 -0.762)
			(stroke
				(width 0.1524)
				(type default)
			)
			(layer "B.SilkS")
		)
		(fp_line
			(start -1.524 -0.762)
			(end -1.524 0.762)
			(stroke
				(width 0.1524)
				(type default)
			)
			(layer "B.SilkS")
		)
		(fp_line
			(start 1.524 -0.762)
			(end -1.524 -0.762)
			(stroke
				(width 0.1524)
				(type default)
			)
			(layer "B.SilkS")
		)
		(fp_line
			(start -1.1049 0.724916)
			(end -1.1049 -0.724916)
			(stroke
				(width 0.1)
				(type default)
			)
			(layer "B.Fab")
		)
		(fp_line
			(start 1.1049 0.724916)
			(end -1.1049 0.724916)
			(stroke
				(width 0.1)
				(type default)
			)
			(layer "B.Fab")
		)
		(fp_line
			(start -1.1049 -0.724916)
			(end 1.1049 -0.724916)
			(stroke
				(width 0.1)
				(type default)
			)
			(layer "B.Fab")
		)
		(fp_line
			(start 1.1049 -0.724916)
			(end 1.1049 0.724916)
			(stroke
				(width 0.1)
				(type default)
			)
			(layer "B.Fab")
		)
		(pad "1" smd rect
			(at 0.889 0 270)
			(size 1.016 1.27)
			(layers "B.Cu" "B.Mask" "B.Paste")
			(net "P12V_S3_AUX_CPU0_NVDIMM")
		)
		(pad "2" smd rect
			(at -0.889 0 270)
			(size 1.016 1.27)
			(layers "B.Cu" "B.Mask" "B.Paste")
			(net "GND")
		)
	)
	(footprint ""
		(layer "B.Cu")
		(at 369.522502 -210.19389 180)
		(property "Reference" "C528"
			(at 0 0 0)
			(layer "B.SilkS")
			(hide yes)
			(effects
				(font
					(size 1.27 1.27)
				)
				(justify mirror)
			)
		)
		(property "Value" ""
			(at 0 0 0)
			(layer "B.Fab")
			(effects
				(font
					(size 1.27 1.27)
				)
				(justify mirror)
			)
		)
		(duplicate_pad_numbers_are_jumpers no)
		(fp_line
			(start 1.524 0.762)
			(end 1.524 -0.762)
			(stroke
				(width 0.1524)
				(type default)
			)
			(layer "B.SilkS")
		)
		(fp_line
			(start 1.524 -0.762)
			(end -1.524 -0.762)
			(stroke
				(width 0.1524)
				(type default)
			)
			(layer "B.SilkS")
		)
		(fp_line
			(start -1.524 0.762)
			(end 1.524 0.762)
			(stroke
				(width 0.1524)
				(type default)
			)
			(layer "B.SilkS")
		)
		(fp_line
			(start -1.524 -0.762)
			(end -1.524 0.762)
			(stroke
				(width 0.1524)
				(type default)
			)
			(layer "B.SilkS")
		)
		(fp_line
			(start 1.1049 0.724916)
			(end -1.1049 0.724916)
			(stroke
				(width 0.1)
				(type default)
			)
			(layer "B.Fab")
		)
		(fp_line
			(start 1.1049 -0.724916)
			(end 1.1049 0.724916)
			(stroke
				(width 0.1)
				(type default)
			)
			(layer "B.Fab")
		)
		(fp_line
			(start -1.1049 0.724916)
			(end -1.1049 -0.724916)
			(stroke
				(width 0.1)
				(type default)
			)
			(layer "B.Fab")
		)
		(fp_line
			(start -1.1049 -0.724916)
			(end 1.1049 -0.724916)
			(stroke
				(width 0.1)
				(type default)
			)
			(layer "B.Fab")
		)
		(pad "1" smd rect
			(at 0.889 0 180)
			(size 1.016 1.27)
			(layers "B.Cu" "B.Mask" "B.Paste")
			(net "PVCCINFAON_CPU0")
		)
		(pad "2" smd rect
			(at -0.889 0 180)
			(size 1.016 1.27)
			(layers "B.Cu" "B.Mask" "B.Paste")
			(net "GND")
		)
	)
	(footprint ""
		(layer "B.Cu")
		(at 369.485418 -294.009826 180)
		(property "Reference" "C383"
			(at 0 0 0)
			(layer "B.SilkS")
			(hide yes)
			(effects
				(font
					(size 1.27 1.27)
				)
				(justify mirror)
			)
		)
		(property "Value" ""
			(at 0 0 0)
			(layer "B.Fab")
			(effects
				(font
					(size 1.27 1.27)
				)
				(justify mirror)
			)
		)
		(duplicate_pad_numbers_are_jumpers no)
		(fp_line
			(start 1.524 0.762)
			(end 1.524 -0.762)
			(stroke
				(width 0.1524)
				(type default)
			)
			(layer "B.SilkS")
		)
		(fp_line
			(start 1.524 -0.762)
			(end -1.524 -0.762)
			(stroke
				(width 0.1524)
				(type default)
			)
			(layer "B.SilkS")
		)
		(fp_line
			(start -1.524 0.762)
			(end 1.524 0.762)
			(stroke
				(width 0.1524)
				(type default)
			)
			(layer "B.SilkS")
		)
		(fp_line
			(start -1.524 -0.762)
			(end -1.524 0.762)
			(stroke
				(width 0.1524)
				(type default)
			)
			(layer "B.SilkS")
		)
		(fp_line
			(start 1.1049 0.724916)
			(end -1.1049 0.724916)
			(stroke
				(width 0.1)
				(type default)
			)
			(layer "B.Fab")
		)
		(fp_line
			(start 1.1049 -0.724916)
			(end 1.1049 0.724916)
			(stroke
				(width 0.1)
				(type default)
			)
			(layer "B.Fab")
		)
		(fp_line
			(start -1.1049 0.724916)
			(end -1.1049 -0.724916)
			(stroke
				(width 0.1)
				(type default)
			)
			(layer "B.Fab")
		)
		(fp_line
			(start -1.1049 -0.724916)
			(end 1.1049 -0.724916)
			(stroke
				(width 0.1)
				(type default)
			)
			(layer "B.Fab")
		)
		(pad "1" smd rect
			(at 0.889 0 180)
			(size 1.016 1.27)
			(layers "B.Cu" "B.Mask" "B.Paste")
			(net "PVCCIN_CPU0")
		)
		(pad "2" smd rect
			(at -0.889 0 180)
			(size 1.016 1.27)
			(layers "B.Cu" "B.Mask" "B.Paste")
			(net "GND")
		)
	)
	(footprint ""
		(layer "B.Cu")
		(at 121.545604 -296.05478 180)
		(property "Reference" "C354"
			(at 0 0 0)
			(layer "B.SilkS")
			(hide yes)
			(effects
				(font
					(size 1.27 1.27)
				)
				(justify mirror)
			)
		)
		(property "Value" ""
			(at 0 0 0)
			(layer "B.Fab")
			(effects
				(font
					(size 1.27 1.27)
				)
				(justify mirror)
			)
		)
		(duplicate_pad_numbers_are_jumpers no)
		(fp_line
			(start 1.524 0.762)
			(end 1.524 -0.762)
			(stroke
				(width 0.1524)
				(type default)
			)
			(layer "B.SilkS")
		)
		(fp_line
			(start 1.524 -0.762)
			(end -1.524 -0.762)
			(stroke
				(width 0.1524)
				(type default)
			)
			(layer "B.SilkS")
		)
		(fp_line
			(start -1.524 0.762)
			(end 1.524 0.762)
			(stroke
				(width 0.1524)
				(type default)
			)
			(layer "B.SilkS")
		)
		(fp_line
			(start -1.524 -0.762)
			(end -1.524 0.762)
			(stroke
				(width 0.1524)
				(type default)
			)
			(layer "B.SilkS")
		)
		(fp_line
			(start 1.1049 0.724916)
			(end -1.1049 0.724916)
			(stroke
				(width 0.1)
				(type default)
			)
			(layer "B.Fab")
		)
		(fp_line
			(start 1.1049 -0.724916)
			(end 1.1049 0.724916)
			(stroke
				(width 0.1)
				(type default)
			)
			(layer "B.Fab")
		)
		(fp_line
			(start -1.1049 0.724916)
			(end -1.1049 -0.724916)
			(stroke
				(width 0.1)
				(type default)
			)
			(layer "B.Fab")
		)
		(fp_line
			(start -1.1049 -0.724916)
			(end 1.1049 -0.724916)
			(stroke
				(width 0.1)
				(type default)
			)
			(layer "B.Fab")
		)
		(pad "1" smd rect
			(at 0.889 0 180)
			(size 1.016 1.27)
			(layers "B.Cu" "B.Mask" "B.Paste")
			(net "PVCCIN_CPU1")
		)
		(pad "2" smd rect
			(at -0.889 0 180)
			(size 1.016 1.27)
			(layers "B.Cu" "B.Mask" "B.Paste")
			(net "GND")
		)
	)
	(footprint ""
		(layer "B.Cu")
		(at 243.003832 -97.552764 -90)
		(property "Reference" "C1309"
			(at 0 0 90)
			(layer "B.SilkS")
			(hide yes)
			(effects
				(font
					(size 1.27 1.27)
				)
				(justify mirror)
			)
		)
		(property "Value" ""
			(at 0 0 90)
			(layer "B.Fab")
			(effects
				(font
					(size 1.27 1.27)
				)
				(justify mirror)
			)
		)
		(duplicate_pad_numbers_are_jumpers no)
		(fp_line
			(start -1.2954 0.5842)
			(end 1.2954 0.5842)
			(stroke
				(width 0.1524)
				(type default)
			)
			(layer "B.SilkS")
		)
		(fp_line
			(start 1.2954 0.5842)
			(end 1.2954 -0.5842)
			(stroke
				(width 0.1524)
				(type default)
			)
			(layer "B.SilkS")
		)
		(fp_line
			(start -1.2954 -0.5842)
			(end -1.2954 0.5842)
			(stroke
				(width 0.1524)
				(type default)
			)
			(layer "B.SilkS")
		)
		(fp_line
			(start 0 -0.5842)
			(end 0 0.5842)
			(stroke
				(width 0.1524)
				(type default)
			)
			(layer "B.SilkS")
		)
		(fp_line
			(start 1.2954 -0.5842)
			(end -1.2954 -0.5842)
			(stroke
				(width 0.1524)
				(type default)
			)
			(layer "B.SilkS")
		)
		(fp_line
			(start -0.8636 0.4572)
			(end 0.8636 0.4572)
			(stroke
				(width 0.1)
				(type default)
			)
			(layer "B.Fab")
		)
		(fp_line
			(start 0.8636 0.4572)
			(end 0.8636 0.4064)
			(stroke
				(width 0.1)
				(type default)
			)
			(layer "B.Fab")
		)
		(fp_line
			(start -1.1938 0.4064)
			(end -0.8636 0.4064)
			(stroke
				(width 0.1)
				(type default)
			)
			(layer "B.Fab")
		)
		(fp_line
			(start -0.8636 0.4064)
			(end -0.8636 0.4572)
			(stroke
				(width 0.1)
				(type default)
			)
			(layer "B.Fab")
		)
		(fp_line
			(start 0.8636 0.4064)
			(end 1.1938 0.4064)
			(stroke
				(width 0.1)
				(type default)
			)
			(layer "B.Fab")
		)
		(fp_line
			(start 1.1938 0.4064)
			(end 1.1938 -0.4064)
			(stroke
				(width 0.1)
				(type default)
			)
			(layer "B.Fab")
		)
		(fp_line
			(start -1.1938 -0.4064)
			(end -1.1938 0.4064)
			(stroke
				(width 0.1)
				(type default)
			)
			(layer "B.Fab")
		)
		(fp_line
			(start -0.8636 -0.4064)
			(end -1.1938 -0.4064)
			(stroke
				(width 0.1)
				(type default)
			)
			(layer "B.Fab")
		)
		(fp_line
			(start 0.8636 -0.4064)
			(end 0.8636 -0.4572)
			(stroke
				(width 0.1)
				(type default)
			)
			(layer "B.Fab")
		)
		(fp_line
			(start 1.1938 -0.4064)
			(end 0.8636 -0.4064)
			(stroke
				(width 0.1)
				(type default)
			)
			(layer "B.Fab")
		)
		(fp_line
			(start -0.8636 -0.4572)
			(end -0.8636 -0.4064)
			(stroke
				(width 0.1)
				(type default)
			)
			(layer "B.Fab")
		)
		(fp_line
			(start 0.8636 -0.4572)
			(end -0.8636 -0.4572)
			(stroke
				(width 0.1)
				(type default)
			)
			(layer "B.Fab")
		)
		(pad "1" smd rect
			(at 0.7366 0 180)
			(size 0.7112 0.8128)
			(layers "B.Cu" "B.Mask" "B.Paste")
			(net "P3V3_AUX_CLK_GEN_VDDXTAL_CK440")
		)
		(pad "2" smd rect
			(at -0.7366 0 180)
			(size 0.7112 0.8128)
			(layers "B.Cu" "B.Mask" "B.Paste")
			(net "GND")
		)
	)
	(footprint ""
		(layer "B.Cu")
		(at 193.60388 -103.685848 180)
		(property "Reference" "R1435"
			(at 0 0 0)
			(layer "B.SilkS")
			(hide yes)
			(effects
				(font
					(size 1.27 1.27)
				)
				(justify mirror)
			)
		)
		(property "Value" ""
			(at 0 0 0)
			(layer "B.Fab")
			(effects
				(font
					(size 1.27 1.27)
				)
				(justify mirror)
			)
		)
		(duplicate_pad_numbers_are_jumpers no)
		(fp_line
			(start 0.7874 0.4064)
			(end 0.7874 -0.4064)
			(stroke
				(width 0.1524)
				(type default)
			)
			(layer "B.SilkS")
		)
		(fp_line
			(start 0.7874 -0.4064)
			(end -0.7874 -0.4064)
			(stroke
				(width 0.1524)
				(type default)
			)
			(layer "B.SilkS")
		)
		(fp_line
			(start -0.7874 0.4064)
			(end 0.7874 0.4064)
			(stroke
				(width 0.1524)
				(type default)
			)
			(layer "B.SilkS")
		)
		(fp_line
			(start -0.7874 -0.4064)
			(end -0.7874 0.4064)
			(stroke
				(width 0.1524)
				(type default)
			)
			(layer "B.SilkS")
		)
		(fp_line
			(start 0.67945 0.3048)
			(end 0.67945 -0.305054)
			(stroke
				(width 0.1)
				(type default)
			)
			(layer "B.Fab")
		)
		(fp_line
			(start 0.67945 -0.305054)
			(end 0.12065 -0.305054)
			(stroke
				(width 0.1)
				(type default)
			)
			(layer "B.Fab")
		)
		(fp_line
			(start 0.12065 0.3048)
			(end 0.67945 0.3048)
			(stroke
				(width 0.1)
				(type default)
			)
			(layer "B.Fab")
		)
		(fp_line
			(start 0.12065 0.2794)
			(end 0.12065 0.3048)
			(stroke
				(width 0.1)
				(type default)
			)
			(layer "B.Fab")
		)
		(fp_line
			(start 0.12065 -0.2794)
			(end -0.12065 -0.2794)
			(stroke
				(width 0.1)
				(type default)
			)
			(layer "B.Fab")
		)
		(fp_line
			(start 0.12065 -0.305054)
			(end 0.12065 -0.2794)
			(stroke
				(width 0.1)
				(type default)
			)
			(layer "B.Fab")
		)
		(fp_line
			(start -0.120396 0.3048)
			(end -0.120396 0.2794)
			(stroke
				(width 0.1)
				(type default)
			)
			(layer "B.Fab")
		)
		(fp_line
			(start -0.120396 0.2794)
			(end 0.12065 0.2794)
			(stroke
				(width 0.1)
				(type default)
			)
			(layer "B.Fab")
		)
		(fp_line
			(start -0.12065 -0.2794)
			(end -0.12065 -0.3048)
			(stroke
				(width 0.1)
				(type default)
			)
			(layer "B.Fab")
		)
		(fp_line
			(start -0.12065 -0.3048)
			(end -0.67945 -0.3048)
			(stroke
				(width 0.1)
				(type default)
			)
			(layer "B.Fab")
		)
		(fp_line
			(start -0.67945 0.3048)
			(end -0.120396 0.3048)
			(stroke
				(width 0.1)
				(type default)
			)
			(layer "B.Fab")
		)
		(fp_line
			(start -0.67945 -0.3048)
			(end -0.67945 0.3048)
			(stroke
				(width 0.1)
				(type default)
			)
			(layer "B.Fab")
		)
		(pad "1" smd circle
			(at 0.40005 0)
			(size 0 0)
			(layers "B.Cu" "B.Mask" "B.Paste")
			(net "FM_ADR_TRIGGER_N")
		)
		(pad "2" smd circle
			(at -0.40005 0)
			(size 0 0)
			(layers "B.Cu" "B.Mask" "B.Paste")
			(net "P3V3_AUX")
		)
	)
	(footprint ""
		(layer "B.Cu")
		(at 187.04052 -358.11587 180)
		(property "Reference" "PC1684"
			(at 0 0 0)
			(layer "B.SilkS")
			(hide yes)
			(effects
				(font
					(size 1.27 1.27)
				)
				(justify mirror)
			)
		)
		(property "Value" ""
			(at 0 0 0)
			(layer "B.Fab")
			(effects
				(font
					(size 1.27 1.27)
				)
				(justify mirror)
			)
		)
		(duplicate_pad_numbers_are_jumpers no)
		(fp_line
			(start 1.524 0.762)
			(end 1.524 -0.762)
			(stroke
				(width 0.1524)
				(type default)
			)
			(layer "B.SilkS")
		)
		(fp_line
			(start 1.524 -0.762)
			(end -1.524 -0.762)
			(stroke
				(width 0.1524)
				(type default)
			)
			(layer "B.SilkS")
		)
		(fp_line
			(start -1.524 0.762)
			(end 1.524 0.762)
			(stroke
				(width 0.1524)
				(type default)
			)
			(layer "B.SilkS")
		)
		(fp_line
			(start -1.524 -0.762)
			(end -1.524 0.762)
			(stroke
				(width 0.1524)
				(type default)
			)
			(layer "B.SilkS")
		)
		(fp_line
			(start 1.1049 0.724916)
			(end -1.1049 0.724916)
			(stroke
				(width 0.1)
				(type default)
			)
			(layer "B.Fab")
		)
		(fp_line
			(start 1.1049 -0.724916)
			(end 1.1049 0.724916)
			(stroke
				(width 0.1)
				(type default)
			)
			(layer "B.Fab")
		)
		(fp_line
			(start -1.1049 0.724916)
			(end -1.1049 -0.724916)
			(stroke
				(width 0.1)
				(type default)
			)
			(layer "B.Fab")
		)
		(fp_line
			(start -1.1049 -0.724916)
			(end 1.1049 -0.724916)
			(stroke
				(width 0.1)
				(type default)
			)
			(layer "B.Fab")
		)
		(pad "1" smd rect
			(at 0.889 0 180)
			(size 1.016 1.27)
			(layers "B.Cu" "B.Mask" "B.Paste")
			(net "SW_P12V_PVCCFA_EHV_FIVRA_CPU1_R")
		)
		(pad "2" smd rect
			(at -0.889 0 180)
			(size 1.016 1.27)
			(layers "B.Cu" "B.Mask" "B.Paste")
			(net "GND")
		)
	)
)
